# S9S_MB_2U (Grand Teton) — schematic netlist excerpt (pin names and nets, part order shuffled) for the footprints in the layout excerpt that follows; sources: Cadence DE-HDL packaged netlist, KiCad conversion of 03242023_DA0F0TMBIJ0_F0T_Motherboard_J_brd_V01_OCP.brd

J12  SCONN288_ADR50017P087CC  SCONN288_ADR50017-P087CC IO  pkg DDR288S_1-1VXB  page 93
  VIN_BULK0  = P12V_S3_AUX_CPU0_NVDIMM
  RFU0  = TP_CHF_CPU0_DIMM2_FRU_0
  VIN_MGMT  = P3V3_AUX
  HSCL  = I3C_SPD_DDREFGH_CPU0_LVC1_SCL_3
  HSDA  = I3C_SPD_DDREFGH_CPU0_LVC1_SDA
  VSS0  = GND
  DQ0_A  = M_F_CPU0_SA_DQ<0>
  VSS1  = GND
  DQ1_A  = M_F_CPU0_SA_DQ<1>
  VSS2  = GND
  DQS0_A_T  = M_F_CPU0_SA_DQS_DP<0>
  DQS0_A_C  = M_F_CPU0_SA_DQS_DN<0>
  VSS3  = GND
  DQ4_A  = M_F_CPU0_SA_DQ<4>
  VSS4  = GND
  DQ5_A  = M_F_CPU0_SA_DQ<5>
  VSS5  = GND
  DQ8_A  = M_F_CPU0_SA_DQ<8>
  VSS6  = GND
  DQ9_A  = M_F_CPU0_SA_DQ<9>
  VSS7  = GND
  DQS1_A_T  = M_F_CPU0_SA_DQS_DP<1>
  DQS1_A_C  = M_F_CPU0_SA_DQS_DN<1>
  VSS8  = GND
  DQ12_A  = M_F_CPU0_SA_DQ<12>
  VSS9  = GND
  DQ13_A  = M_F_CPU0_SA_DQ<13>
  VSS10  = GND
  DQ16_A  = M_F_CPU0_SA_DQ<16>
  VSS11  = GND
  DQ17_A  = M_F_CPU0_SA_DQ<17>
  VSS12  = GND
  DQS2_A_T  = M_F_CPU0_SA_DQS_DP<2>
  DQS2_A_C  = M_F_CPU0_SA_DQS_DN<2>
  VSS13  = GND
  DQ20_A  = M_F_CPU0_SA_DQ<20>
  VSS14  = GND
  DQ21_A  = M_F_CPU0_SA_DQ<21>
  VSS15  = GND
  DQ24_A  = M_F_CPU0_SA_DQ<24>
  VSS16  = GND
  DQ25_A  = M_F_CPU0_SA_DQ<25>
  VSS17  = GND
  DQS3_A_T  = M_F_CPU0_SA_DQS_DP<3>
  DQS3_A_C  = M_F_CPU0_SA_DQS_DN<3>
  VSS18  = GND
  DQ28_A  = M_F_CPU0_SA_DQ<28>
  VSS19  = GND
  DQ29_A  = M_F_CPU0_SA_DQ<29>
  VSS20  = GND
  CB0_A  = M_F_CPU0_SA_CB<0>
  VSS21  = GND
  CB1_A  = M_F_CPU0_SA_CB<1>
  VSS22  = GND
  DQS4_A_T  = M_F_CPU0_SA_DQS_DP<4>
  DQS4_A_C  = M_F_CPU0_SA_DQS_DN<4>
  VSS23  = GND
  CB4_A  = M_F_CPU0_SA_CB<4>
  VSS24  = GND
  CB5_A  = M_F_CPU0_SA_CB<5>
  VSS25  = GND
  ALERT_N  = M_F_CPU0_ALERT_N
  VSS26  = GND
  CS0_A_N  = M_F_CPU0_SA_CS_N<2>
  VSS27  = GND
  CA0_A  = M_F_CPU0_SA_CA<0>
  VSS28  = GND
  CA2_A  = M_F_CPU0_SA_CA<2>
  VSS29  = GND
  CA4_A  = M_F_CPU0_SA_CA<4>
  VSS30  = GND
  CA6_A  = M_F_CPU0_SA_CA<6>
  VSS31  = GND
  PAR_A  = M_F_CPU0_SA_PAR
  VSS32  = GND
  CA0_B  = M_F_CPU0_SB_CA<0>
  VSS33  = GND
  CA2_B  = M_F_CPU0_SB_CA<2>
  VSS34  = GND
  CA4_B  = M_F_CPU0_SB_CA<4>
  VSS35  = GND
  CA6_B  = M_F_CPU0_SB_CA<6>
  VSS36  = GND
  CS0_B_N  = M_F_CPU0_SB_CS_N<2>
  VSS37  = GND
  \lbd||rsp_a_n\  = M_F_CPU0_SA_RSP<1>
  \lbs||rsp_b_n\  = M_F_CPU0_SB_RSP<1>
  VSS38  = GND
  CB4_B  = M_F_CPU0_SB_CB<4>
  VSS39  = GND
  CB5_B  = M_F_CPU0_SB_CB<5>
  VSS40  = GND
  \dqs9_b_t||tdqs9_b_t||dbi4_b_n\  = M_F_CPU0_SB_DQS_DP<9>
  \dqs9_b_c||tdqs9_b_c\  = M_F_CPU0_SB_DQS_DN<9>
  VSS41  = GND
  CB0_B  = M_F_CPU0_SB_CB<0>
  VSS42  = GND
  CB1_B  = M_F_CPU0_SB_CB<1>
  VSS43  = GND
  DQ0_B  = M_F_CPU0_SB_DQ<0>
  VSS44  = GND
  DQ1_B  = M_F_CPU0_SB_DQ<1>
  VSS45  = GND
  DQS0_B_T  = M_F_CPU0_SB_DQS_DP<0>
  DQS0_B_C  = M_F_CPU0_SB_DQS_DN<0>
  VSS46  = GND
  DQ4_B  = M_F_CPU0_SB_DQ<4>
  VSS47  = GND
  DQ5_B  = M_F_CPU0_SB_DQ<5>
  VSS48  = GND
  DQ8_B  = M_F_CPU0_SB_DQ<8>
  VSS49  = GND
  DQ9_B  = M_F_CPU0_SB_DQ<9>
  VSS50  = GND
  DQS1_B_T  = M_F_CPU0_SB_DQS_DP<1>
  DQS1_B_C  = M_F_CPU0_SB_DQS_DN<1>
  VSS51  = GND
  DQ12_B  = M_F_CPU0_SB_DQ<12>
  VSS52  = GND
  DQ13_B  = M_F_CPU0_SB_DQ<13>
  VSS53  = GND
  DQ16_B  = M_F_CPU0_SB_DQ<16>
  VSS54  = GND
  DQ17_B  = M_F_CPU0_SB_DQ<17>
  VSS55  = GND
  DQS2_B_T  = M_F_CPU0_SB_DQS_DP<2>
  DQS2_B_C  = M_F_CPU0_SB_DQS_DN<2>
  VSS56  = GND
  DQ20_B  = M_F_CPU0_SB_DQ<20>
  VSS57  = GND
  DQ21_B  = M_F_CPU0_SB_DQ<21>
  VSS58  = GND
  DQ24_B  = M_F_CPU0_SB_DQ<24>
  VSS59  = GND
  DQ25_B  = M_F_CPU0_SB_DQ<25>
  VSS60  = GND
  DQS3_B_T  = M_F_CPU0_SB_DQS_DP<3>
  DQS3_B_C  = M_F_CPU0_SB_DQS_DN<3>
  VSS61  = GND
  DQ28_B  = M_F_CPU0_SB_DQ<28>
  VSS62  = GND
  DQ29_B  = M_F_CPU0_SB_DQ<29>
  VSS63  = GND
  RFU1  = TP_CHF_CPU0_DIMM2_FRU_1
  VIN_BULK1  = P12V_S3_AUX_CPU0_NVDIMM
  VIN_BULK2  = P12V_S3_AUX_CPU0_NVDIMM
  \pwr_good||fail_n\  = PWRGD_CHF_CPU0_DIMM2
  HSA  = PD_CHF_CPU0_DIMM2_SAA
  RFU2  = TP_CHF_CPU0_DIMM2_FRU_2
  RFU3  = TP_CHF_CPU0_DIMM2_FRU_3
  VSS64  = GND
  DQ2_A  = M_F_CPU0_SA_DQ<2>
  VSS65  = GND
  DQ3_A  = M_F_CPU0_SA_DQ<3>
  VSS66  = GND
  \dqs5_a_c||tdqs5_a_c||dqs5_a_t||tdqs5_a_t\  = M_F_CPU0_SA_DQS_DN<5>
  \dqs5_a_t||tdqs5_a_t\  = M_F_CPU0_SA_DQS_DP<5>
  VSS67  = GND
  DQ6_A  = M_F_CPU0_SA_DQ<6>
  VSS68  = GND
  DQ7_A  = M_F_CPU0_SA_DQ<7>
  VSS69  = GND
  DQ10_A  = M_F_CPU0_SA_DQ<10>
  VSS70  = GND
  DQ11_A  = M_F_CPU0_SA_DQ<11>
  VSS71  = GND
  \dqs6_a_c||tdqs6_a_c||dqs6_a_t||tdqs6_a_t\  = M_F_CPU0_SA_DQS_DN<6>
  \dqs6_a_t||tdqs6_a_t\  = M_F_CPU0_SA_DQS_DP<6>
  VSS72  = GND
  DQ14_A  = M_F_CPU0_SA_DQ<14>
  VSS73  = GND
  DQ15_A  = M_F_CPU0_SA_DQ<15>
  VSS74  = GND
  DQ18_A  = M_F_CPU0_SA_DQ<18>
  VSS75  = GND
  DQ19_A  = M_F_CPU0_SA_DQ<19>
  VSS76  = GND
  \dqs7_a_c||tdqs7_a_c\  = M_F_CPU0_SA_DQS_DN<7>
  \dqs7_a_t||tdqs7_a_t\  = M_F_CPU0_SA_DQS_DP<7>
  VSS77  = GND
  DQ22_A  = M_F_CPU0_SA_DQ<22>
  VSS78  = GND
  DQ23_A  = M_F_CPU0_SA_DQ<23>
  VSS79  = GND
  DQ26_A  = M_F_CPU0_SA_DQ<26>
  VSS80  = GND
  DQ27_A  = M_F_CPU0_SA_DQ<27>
  VSS81  = GND
  \dqs8_a_c||tdqs8_a_c\  = M_F_CPU0_SA_DQS_DN<8>
  \dqs8_a_t||tdqs8_a_t\  = M_F_CPU0_SA_DQS_DP<8>
  VSS82  = GND
  DQ30_A  = M_F_CPU0_SA_DQ<30>
  VSS83  = GND
  DQ31_A  = M_F_CPU0_SA_DQ<31>
  VSS84  = GND
  CB2_A  = M_F_CPU0_SA_CB<2>
  VSS85  = GND
  CB3_A  = M_F_CPU0_SA_CB<3>
  VSS86  = GND
  \dqs9_a_c||tdqs9_a_c\  = M_F_CPU0_SA_DQS_DN<9>
  \dqs9_a_t||tdqs9_a_t\  = M_F_CPU0_SA_DQS_DP<9>
  VSS87  = GND
  CB6_A  = M_F_CPU0_SA_CB<6>
  VSS88  = GND
  CB7_A  = M_F_CPU0_SA_CB<7>
  VSS89  = GND
  RESET_N  = RST_M_EF_CPU0_FPGA_N
  VSS90  = GND
  CS1_A_N  = M_F_CPU0_SA_CS_N<3>
  VSS91  = GND
  CA1_A  = M_F_CPU0_SA_CA<1>
  VSS92  = GND
  CA3_A  = M_F_CPU0_SA_CA<3>
  VSS93  = GND
  CA5_A  = M_F_CPU0_SA_CA<5>
  VSS94  = GND
  CK_T  = M_F_CPU0_CLK_DP<1>
  CK_C  = M_F_CPU0_CLK_DN<1>
  VSS95  = GND
  RFU4  = TP_CHF_CPU0_DIMM2_FRU_4
  CA1_B  = M_F_CPU0_SB_CA<1>
  VSS96  = GND
  CA3_B  = M_F_CPU0_SB_CA<3>
  VSS97  = GND
  CA5_B  = M_F_CPU0_SB_CA<5>
  VSS98  = GND
  PAR_B  = M_F_CPU0_SB_PAR
  VSS99  = GND
  CS1_B_N  = M_F_CPU0_SB_CS_N<3>
  VSS100  = GND
  RFU5  = TP_CHF_CPU0_DIMM2_FRU_5
  RFU6  = TP_CHF_CPU0_DIMM2_FRU_6
  VSS101  = GND
  CB6_B  = M_F_CPU0_SB_CB<6>
  VSS102  = GND
  CB7_B  = M_F_CPU0_SB_CB<7>
  VSS103  = GND
  DQS4_B_C  = M_F_CPU0_SB_DQS_DN<4>
  DQS4_B_T  = M_F_CPU0_SB_DQS_DP<4>
  VSS104  = GND
  CB2_B  = M_F_CPU0_SB_CB<2>
  VSS105  = GND
  CB3_B  = M_F_CPU0_SB_CB<3>
  VSS106  = GND
  DQ2_B  = M_F_CPU0_SB_DQ<2>
  VSS107  = GND
  DQ3_B  = M_F_CPU0_SB_DQ<3>
  VSS108  = GND
  \dqs5_b_c||tdqs5_b_c\  = M_F_CPU0_SB_DQS_DN<5>
  \dqs5_b_t||tdqs5_b_t\  = M_F_CPU0_SB_DQS_DP<5>
  VSS109  = GND
  DQ6_B  = M_F_CPU0_SB_DQ<6>
  VSS110  = GND
  DQ7_B  = M_F_CPU0_SB_DQ<7>
  VSS111  = GND
  DQ10_B  = M_F_CPU0_SB_DQ<10>
  VSS112  = GND
  DQ11_B  = M_F_CPU0_SB_DQ<11>
  VSS113  = GND
  \dqs6_b_c||tdqs6_b_c\  = M_F_CPU0_SB_DQS_DN<6>
  \dqs6_b_t||tdqs6_b_t\  = M_F_CPU0_SB_DQS_DP<6>
  VSS114  = GND
  DQ14_B  = M_F_CPU0_SB_DQ<14>
  VSS115  = GND
  DQ15_B  = M_F_CPU0_SB_DQ<15>
  VSS116  = GND
  DQ18_B  = M_F_CPU0_SB_DQ<18>
  VSS117  = GND
  DQ19_B  = M_F_CPU0_SB_DQ<19>
  VSS118  = GND
  \dqs7_b_c||tdqs7_b_c\  = M_F_CPU0_SB_DQS_DN<7>
  \dqs7_b_t||tdqs7_b_t\  = M_F_CPU0_SB_DQS_DP<7>
  VSS119  = GND
  DQ22_B  = M_F_CPU0_SB_DQ<22>
  VSS120  = GND
  DQ23_B  = M_F_CPU0_SB_DQ<23>
  VSS121  = GND
  DQ26_B  = M_F_CPU0_SB_DQ<26>
  VSS122  = GND
  DQ27_B  = M_F_CPU0_SB_DQ<27>
  VSS123  = GND
  \dqs8_b_c||tdqs8_b_c\  = M_F_CPU0_SB_DQS_DN<8>
  \dqs8_b_t||tdqs8_b_t\  = M_F_CPU0_SB_DQS_DP<8>
  VSS124  = GND
  DQ30_B  = M_F_CPU0_SB_DQ<30>
  VSS125  = GND
  DQ31_B  = M_F_CPU0_SB_DQ<31>
  VSS126  = GND
  G1  = GND
  G2  = GND
  G3  = GND

(kicad_pcb
	(version 20260206)
	(generator "pcbnew")
	(generator_version "10.0")
	(general
		(thickness 1.6)
		(legacy_teardrops no)
	)
	(paper "A4")
	(title_block
		(title "03242023_DA0F0TMBIJ0_F0T_Motherboard_J_brd_V01_OCP.brd")
		(comment 1 "Grand Teton / footprint 3198 of 6105 (J12), pads 275-291 of 291")
	)
	(layers
		(0 "F.Cu" signal "TOP")
		(4 "In1.Cu" signal "GND")
		(6 "In2.Cu" signal "IN1")
		(8 "In3.Cu" signal "GND1")
		(10 "In4.Cu" signal "IN2")
		(12 "In5.Cu" signal "GND2")
		(14 "In6.Cu" signal "IN3")
		(16 "In7.Cu" signal "GND3")
		(18 "In8.Cu" signal "VCC")
		(20 "In9.Cu" signal "VCC1")
		(22 "In10.Cu" signal "GND4")
		(24 "In11.Cu" signal "IN4")
		(26 "In12.Cu" signal "GND5")
		(28 "In13.Cu" signal "IN5")
		(30 "In14.Cu" signal "GND6")
		(32 "In15.Cu" signal "IN6")
		(34 "In16.Cu" signal "GND7")
		(2 "B.Cu" signal "BOTTOM")
		(9 "F.Adhes" user "F.Adhesive")
		(11 "B.Adhes" user "B.Adhesive")
		(13 "F.Paste" user "Package Geometry/Pastemask Top")
		(15 "B.Paste" user "Package Geometry/Pastemask Bottom")
		(5 "F.SilkS" user "Ref Des/Silkscreen Top")
		(7 "B.SilkS" user "Ref Des/Silkscreen Bottom")
		(1 "F.Mask" user "Board Geometry/Soldermask Top")
		(3 "B.Mask" user "Board Geometry/Soldermask Bottom")
		(17 "Dwgs.User" user "User.Drawings")
		(19 "Cmts.User" user "User.Comments")
		(21 "Eco1.User" user "User.Eco1")
		(23 "Eco2.User" user "User.Eco2")
		(25 "Edge.Cuts" user "Board Geometry/Outline")
		(27 "Margin" user)
		(31 "F.CrtYd" user "Package Geometry/Place Bound Top")
		(29 "B.CrtYd" user "Package Geometry/Place Bound Bottom")
		(35 "F.Fab" user "Ref Des/Assembly Top")
		(33 "B.Fab" user "Ref Des/Assembly Bottom")
	)
	(footprint ""
		(layer "F.Cu")
		(at 423.890948 -258.091686)
		(property "Reference" "J12"
			(at -3.683 -81.702148 0)
			(unlocked yes)
			(layer "F.SilkS")
			(effects
				(font
					(size 0.7874 0.5842)
					(thickness 0.1524)
				)
				(justify left)
			)
		)
		(property "Value" ""
			(at 0 0 0)
			(layer "F.Fab")
			(effects
				(font
					(size 1.27 1.27)
				)
			)
		)
		(duplicate_pad_numbers_are_jumpers no)
		(pad "275" smd rect
			(at 2.050034 52.274978 270)
			(size 0.519938 1.4986)
			(layers "F.Cu" "F.Mask" "F.Paste")
			(net "GND")
		)
		(pad "276" smd rect
			(at 2.050034 53.125116 270)
			(size 0.519938 1.4986)
			(layers "F.Cu" "F.Mask" "F.Paste")
			(net "M_F_CPU0_SB_DQ<23>")
		)
		(pad "277" smd rect
			(at 2.050034 53.975 270)
			(size 0.519938 1.4986)
			(layers "F.Cu" "F.Mask" "F.Paste")
			(net "GND")
		)
		(pad "278" smd rect
			(at 2.050034 54.824884 270)
			(size 0.519938 1.4986)
			(layers "F.Cu" "F.Mask" "F.Paste")
			(net "M_F_CPU0_SB_DQ<26>")
		)
		(pad "279" smd rect
			(at 2.050034 55.675022 270)
			(size 0.519938 1.4986)
			(layers "F.Cu" "F.Mask" "F.Paste")
			(net "GND")
		)
		(pad "280" smd rect
			(at 2.050034 56.524906 270)
			(size 0.519938 1.4986)
			(layers "F.Cu" "F.Mask" "F.Paste")
			(net "M_F_CPU0_SB_DQ<27>")
		)
		(pad "281" smd rect
			(at 2.050034 57.375044 270)
			(size 0.519938 1.4986)
			(layers "F.Cu" "F.Mask" "F.Paste")
			(net "GND")
		)
		(pad "282" smd rect
			(at 2.050034 58.224928 270)
			(size 0.519938 1.4986)
			(layers "F.Cu" "F.Mask" "F.Paste")
			(net "M_F_CPU0_SB_DQS_DN<8>")
		)
		(pad "283" smd rect
			(at 2.050034 59.075066 270)
			(size 0.519938 1.4986)
			(layers "F.Cu" "F.Mask" "F.Paste")
			(net "M_F_CPU0_SB_DQS_DP<8>")
		)
		(pad "284" smd rect
			(at 2.050034 59.92495 270)
			(size 0.519938 1.4986)
			(layers "F.Cu" "F.Mask" "F.Paste")
			(net "GND")
		)
		(pad "285" smd rect
			(at 2.050034 60.775088 270)
			(size 0.519938 1.4986)
			(layers "F.Cu" "F.Mask" "F.Paste")
			(net "M_F_CPU0_SB_DQ<30>")
		)
		(pad "286" smd rect
			(at 2.050034 61.624972 270)
			(size 0.519938 1.4986)
			(layers "F.Cu" "F.Mask" "F.Paste")
			(net "GND")
		)
		(pad "287" smd rect
			(at 2.050034 62.47511 270)
			(size 0.519938 1.4986)
			(layers "F.Cu" "F.Mask" "F.Paste")
			(net "M_F_CPU0_SB_DQ<31>")
		)
		(pad "288" smd rect
			(at 2.050034 63.324994 270)
			(size 0.519938 1.4986)
			(layers "F.Cu" "F.Mask" "F.Paste")
			(net "GND")
		)
		(pad "G1" thru_hole oval
			(at 0 -68.97497)
			(size 2.8194 1.5748)
			(drill oval 2.4384 1.1938)
			(layers "*.Cu" "*.Mask")
			(remove_unused_layers no)
			(net "GND")
			(clearance 0.127)
			(thermal_gap 0.127)
		)
		(pad "G2" thru_hole oval
			(at 0 3.875024)
			(size 2.8194 1.5748)
			(drill oval 2.4384 1.1938)
			(layers "*.Cu" "*.Mask")
			(remove_unused_layers no)
			(net "GND")
			(clearance 0.127)
			(thermal_gap 0.127)
		)
		(pad "G3" thru_hole oval
			(at 0 68.97497)
			(size 2.8194 1.5748)
			(drill oval 2.4384 1.1938)
			(layers "*.Cu" "*.Mask")
			(remove_unused_layers no)
			(net "GND")
			(clearance 0.127)
			(thermal_gap 0.127)
		)
	)
)
